(kicad_pcb
	(version 20260206)
	(generator "pcbnew")
	(generator_version "10.0")
	(general
		(thickness 1.6)
		(legacy_teardrops no)
	)
	(paper "A4")
	(title_block
		(title "03242023_DA0F0TMBIJ0_F0T_Motherboard_J_brd_V01_OCP.brd")
		(comment 1 "Grand Teton / footprints 308-314 of 6105")
	)
	(layers
		(0 "F.Cu" signal "TOP")
		(4 "In1.Cu" signal "GND")
		(6 "In2.Cu" signal "IN1")
		(8 "In3.Cu" signal "GND1")
		(10 "In4.Cu" signal "IN2")
		(12 "In5.Cu" signal "GND2")
		(14 "In6.Cu" signal "IN3")
		(16 "In7.Cu" signal "GND3")
		(18 "In8.Cu" signal "VCC")
		(20 "In9.Cu" signal "VCC1")
		(22 "In10.Cu" signal "GND4")
		(24 "In11.Cu" signal "IN4")
		(26 "In12.Cu" signal "GND5")
		(28 "In13.Cu" signal "IN5")
		(30 "In14.Cu" signal "GND6")
		(32 "In15.Cu" signal "IN6")
		(34 "In16.Cu" signal "GND7")
		(2 "B.Cu" signal "BOTTOM")
		(9 "F.Adhes" user "F.Adhesive")
		(11 "B.Adhes" user "B.Adhesive")
		(13 "F.Paste" user "Package Geometry/Pastemask Top")
		(15 "B.Paste" user "Package Geometry/Pastemask Bottom")
		(5 "F.SilkS" user "Ref Des/Silkscreen Top")
		(7 "B.SilkS" user "Ref Des/Silkscreen Bottom")
		(1 "F.Mask" user "Board Geometry/Soldermask Top")
		(3 "B.Mask" user "Board Geometry/Soldermask Bottom")
		(17 "Dwgs.User" user "User.Drawings")
		(19 "Cmts.User" user "User.Comments")
		(21 "Eco1.User" user "User.Eco1")
		(23 "Eco2.User" user "User.Eco2")
		(25 "Edge.Cuts" user "Board Geometry/Outline")
		(27 "Margin" user)
		(31 "F.CrtYd" user "Package Geometry/Place Bound Top")
		(29 "B.CrtYd" user "Package Geometry/Place Bound Bottom")
		(35 "F.Fab" user "Ref Des/Assembly Top")
		(33 "B.Fab" user "Ref Des/Assembly Bottom")
	)
	(footprint ""
		(layer "F.Cu")
		(at 309.522622 -41.900348 180)
		(property "Reference" "R1449"
			(at 0 0 180)
			(layer "F.SilkS")
			(hide yes)
			(effects
				(font
					(size 1.27 1.27)
				)
			)
		)
		(property "Value" ""
			(at 0 0 180)
			(layer "F.Fab")
			(effects
				(font
					(size 1.27 1.27)
				)
			)
		)
		(duplicate_pad_numbers_are_jumpers no)
		(fp_line
			(start 0.7874 0.4064)
			(end -0.7874 0.4064)
			(stroke
				(width 0.1524)
				(type default)
			)
			(layer "F.SilkS")
		)
		(fp_line
			(start 0.7874 -0.4064)
			(end 0.7874 0.4064)
			(stroke
				(width 0.1524)
				(type default)
			)
			(layer "F.SilkS")
		)
		(fp_line
			(start -0.7874 0.4064)
			(end -0.7874 -0.4064)
			(stroke
				(width 0.1524)
				(type default)
			)
			(layer "F.SilkS")
		)
		(fp_line
			(start -0.7874 -0.4064)
			(end 0.7874 -0.4064)
			(stroke
				(width 0.1524)
				(type default)
			)
			(layer "F.SilkS")
		)
		(fp_line
			(start 0.67945 0.3048)
			(end 0.120396 0.3048)
			(stroke
				(width 0.1)
				(type default)
			)
			(layer "F.Fab")
		)
		(fp_line
			(start 0.67945 -0.3048)
			(end 0.67945 0.3048)
			(stroke
				(width 0.1)
				(type default)
			)
			(layer "F.Fab")
		)
		(fp_line
			(start 0.12065 -0.2794)
			(end 0.12065 -0.3048)
			(stroke
				(width 0.1)
				(type default)
			)
			(layer "F.Fab")
		)
		(fp_line
			(start 0.12065 -0.3048)
			(end 0.67945 -0.3048)
			(stroke
				(width 0.1)
				(type default)
			)
			(layer "F.Fab")
		)
		(fp_line
			(start 0.120396 0.3048)
			(end 0.120396 0.2794)
			(stroke
				(width 0.1)
				(type default)
			)
			(layer "F.Fab")
		)
		(fp_line
			(start 0.120396 0.2794)
			(end -0.12065 0.2794)
			(stroke
				(width 0.1)
				(type default)
			)
			(layer "F.Fab")
		)
		(fp_line
			(start -0.12065 0.3048)
			(end -0.67945 0.3048)
			(stroke
				(width 0.1)
				(type default)
			)
			(layer "F.Fab")
		)
		(fp_line
			(start -0.12065 0.2794)
			(end -0.12065 0.3048)
			(stroke
				(width 0.1)
				(type default)
			)
			(layer "F.Fab")
		)
		(fp_line
			(start -0.12065 -0.2794)
			(end 0.12065 -0.2794)
			(stroke
				(width 0.1)
				(type default)
			)
			(layer "F.Fab")
		)
		(fp_line
			(start -0.12065 -0.305054)
			(end -0.12065 -0.2794)
			(stroke
				(width 0.1)
				(type default)
			)
			(layer "F.Fab")
		)
		(fp_line
			(start -0.67945 0.3048)
			(end -0.67945 -0.305054)
			(stroke
				(width 0.1)
				(type default)
			)
			(layer "F.Fab")
		)
		(fp_line
			(start -0.67945 -0.305054)
			(end -0.12065 -0.305054)
			(stroke
				(width 0.1)
				(type default)
			)
			(layer "F.Fab")
		)
		(pad "1" smd circle
			(at -0.40005 0 180)
			(size 0 0)
			(layers "F.Cu" "F.Mask" "F.Paste")
			(net "P3V3_AUX")
		)
		(pad "2" smd circle
			(at 0.40005 0 180)
			(size 0 0)
			(layers "F.Cu" "F.Mask" "F.Paste")
			(net "FM_BIOS_POST_CMPLT_N")
		)
	)
	(footprint ""
		(layer "F.Cu")
		(at 384.99669 -408.517344 -90)
		(property "Reference" "C878"
			(at 0 0 270)
			(layer "F.SilkS")
			(hide yes)
			(effects
				(font
					(size 1.27 1.27)
				)
			)
		)
		(property "Value" ""
			(at 0 0 270)
			(layer "F.Fab")
			(effects
				(font
					(size 1.27 1.27)
				)
			)
		)
		(duplicate_pad_numbers_are_jumpers no)
		(fp_line
			(start -0.299974 0.150114)
			(end -0.299974 -0.150114)
			(stroke
				(width 0.1)
				(type default)
			)
			(layer "F.Fab")
		)
		(fp_line
			(start 0.299974 0.150114)
			(end -0.299974 0.150114)
			(stroke
				(width 0.1)
				(type default)
			)
			(layer "F.Fab")
		)
		(fp_line
			(start -0.299974 -0.150114)
			(end 0.299974 -0.150114)
			(stroke
				(width 0.1)
				(type default)
			)
			(layer "F.Fab")
		)
		(fp_line
			(start 0.299974 -0.150114)
			(end 0.299974 0.150114)
			(stroke
				(width 0.1)
				(type default)
			)
			(layer "F.Fab")
		)
		(pad "1" smd rect
			(at -0.2667 0 270)
			(size 0.3048 0.381)
			(layers "F.Cu" "F.Mask" "F.Paste")
			(net "P5E_CPU0_PE3_TX_C_DN<11>")
		)
		(pad "2" smd rect
			(at 0.2667 0 270)
			(size 0.3048 0.381)
			(layers "F.Cu" "F.Mask" "F.Paste")
			(net "P5E_CPU0_PE3_TX_DN<11>")
		)
	)
	(footprint ""
		(layer "F.Cu")
		(at 415.818828 -174.396654 180)
		(property "Reference" "PC2947"
			(at 0 0 180)
			(layer "F.SilkS")
			(hide yes)
			(effects
				(font
					(size 1.27 1.27)
				)
			)
		)
		(property "Value" ""
			(at 0 0 180)
			(layer "F.Fab")
			(effects
				(font
					(size 1.27 1.27)
				)
			)
		)
		(duplicate_pad_numbers_are_jumpers no)
		(fp_line
			(start 0.7874 0.4064)
			(end -0.7874 0.4064)
			(stroke
				(width 0.1524)
				(type default)
			)
			(layer "F.SilkS")
		)
		(fp_line
			(start 0.7874 -0.4064)
			(end 0.7874 0.4064)
			(stroke
				(width 0.1524)
				(type default)
			)
			(layer "F.SilkS")
		)
		(fp_line
			(start -0.7874 0.4064)
			(end -0.7874 -0.4064)
			(stroke
				(width 0.1524)
				(type default)
			)
			(layer "F.SilkS")
		)
		(fp_line
			(start -0.7874 -0.4064)
			(end 0.7874 -0.4064)
			(stroke
				(width 0.1524)
				(type default)
			)
			(layer "F.SilkS")
		)
		(fp_line
			(start 0.67945 0.3048)
			(end 0.120396 0.3048)
			(stroke
				(width 0.1)
				(type default)
			)
			(layer "F.Fab")
		)
		(fp_line
			(start 0.67945 -0.3048)
			(end 0.67945 0.3048)
			(stroke
				(width 0.1)
				(type default)
			)
			(layer "F.Fab")
		)
		(fp_line
			(start 0.12065 -0.2794)
			(end 0.12065 -0.3048)
			(stroke
				(width 0.1)
				(type default)
			)
			(layer "F.Fab")
		)
		(fp_line
			(start 0.12065 -0.3048)
			(end 0.67945 -0.3048)
			(stroke
				(width 0.1)
				(type default)
			)
			(layer "F.Fab")
		)
		(fp_line
			(start 0.120396 0.3048)
			(end 0.120396 0.2794)
			(stroke
				(width 0.1)
				(type default)
			)
			(layer "F.Fab")
		)
		(fp_line
			(start 0.120396 0.2794)
			(end -0.12065 0.2794)
			(stroke
				(width 0.1)
				(type default)
			)
			(layer "F.Fab")
		)
		(fp_line
			(start -0.12065 0.3048)
			(end -0.67945 0.3048)
			(stroke
				(width 0.1)
				(type default)
			)
			(layer "F.Fab")
		)
		(fp_line
			(start -0.12065 0.2794)
			(end -0.12065 0.3048)
			(stroke
				(width 0.1)
				(type default)
			)
			(layer "F.Fab")
		)
		(fp_line
			(start -0.12065 -0.2794)
			(end 0.12065 -0.2794)
			(stroke
				(width 0.1)
				(type default)
			)
			(layer "F.Fab")
		)
		(fp_line
			(start -0.12065 -0.305054)
			(end -0.12065 -0.2794)
			(stroke
				(width 0.1)
				(type default)
			)
			(layer "F.Fab")
		)
		(fp_line
			(start -0.67945 0.3048)
			(end -0.67945 -0.305054)
			(stroke
				(width 0.1)
				(type default)
			)
			(layer "F.Fab")
		)
		(fp_line
			(start -0.67945 -0.305054)
			(end -0.12065 -0.305054)
			(stroke
				(width 0.1)
				(type default)
			)
			(layer "F.Fab")
		)
		(pad "1" smd circle
			(at -0.40005 0 180)
			(size 0 0)
			(layers "F.Cu" "F.Mask" "F.Paste")
			(net "PVCCFA_EHV_CPU0_PVCC")
		)
		(pad "2" smd circle
			(at 0.40005 0 180)
			(size 0 0)
			(layers "F.Cu" "F.Mask" "F.Paste")
			(net "GND")
		)
	)
	(footprint ""
		(layer "F.Cu")
		(at 325.397368 -402.371052 -90)
		(property "Reference" "C1564"
			(at 0 0 270)
			(layer "F.SilkS")
			(hide yes)
			(effects
				(font
					(size 1.27 1.27)
				)
			)
		)
		(property "Value" ""
			(at 0 0 270)
			(layer "F.Fab")
			(effects
				(font
					(size 1.27 1.27)
				)
			)
		)
		(duplicate_pad_numbers_are_jumpers no)
		(fp_line
			(start -0.299974 0.150114)
			(end -0.299974 -0.150114)
			(stroke
				(width 0.1)
				(type default)
			)
			(layer "F.Fab")
		)
		(fp_line
			(start 0.299974 0.150114)
			(end -0.299974 0.150114)
			(stroke
				(width 0.1)
				(type default)
			)
			(layer "F.Fab")
		)
		(fp_line
			(start -0.299974 -0.150114)
			(end 0.299974 -0.150114)
			(stroke
				(width 0.1)
				(type default)
			)
			(layer "F.Fab")
		)
		(fp_line
			(start 0.299974 -0.150114)
			(end 0.299974 0.150114)
			(stroke
				(width 0.1)
				(type default)
			)
			(layer "F.Fab")
		)
		(pad "1" smd rect
			(at -0.2667 0 270)
			(size 0.3048 0.381)
			(layers "F.Cu" "F.Mask" "F.Paste")
			(net "P5E_CPU0_PE4_TX_C_DN<7>")
		)
		(pad "2" smd rect
			(at 0.2667 0 270)
			(size 0.3048 0.381)
			(layers "F.Cu" "F.Mask" "F.Paste")
			(net "P5E_CPU0_PE4_TX_DN<7>")
		)
	)
	(footprint ""
		(layer "F.Cu")
		(at 223.37141 -73.517506)
		(property "Reference" "PC2216"
			(at 0 0 0)
			(layer "F.SilkS")
			(hide yes)
			(effects
				(font
					(size 1.27 1.27)
				)
			)
		)
		(property "Value" ""
			(at 0 0 0)
			(layer "F.Fab")
			(effects
				(font
					(size 1.27 1.27)
				)
			)
		)
		(duplicate_pad_numbers_are_jumpers no)
		(fp_line
			(start -0.7874 -0.4064)
			(end 0.7874 -0.4064)
			(stroke
				(width 0.1524)
				(type default)
			)
			(layer "F.SilkS")
		)
		(fp_line
			(start -0.7874 0.4064)
			(end -0.7874 -0.4064)
			(stroke
				(width 0.1524)
				(type default)
			)
			(layer "F.SilkS")
		)
		(fp_line
			(start 0.7874 -0.4064)
			(end 0.7874 0.4064)
			(stroke
				(width 0.1524)
				(type default)
			)
			(layer "F.SilkS")
		)
		(fp_line
			(start 0.7874 0.4064)
			(end -0.7874 0.4064)
			(stroke
				(width 0.1524)
				(type default)
			)
			(layer "F.SilkS")
		)
		(fp_line
			(start -0.67945 -0.305054)
			(end -0.12065 -0.305054)
			(stroke
				(width 0.1)
				(type default)
			)
			(layer "F.Fab")
		)
		(fp_line
			(start -0.67945 0.3048)
			(end -0.67945 -0.305054)
			(stroke
				(width 0.1)
				(type default)
			)
			(layer "F.Fab")
		)
		(fp_line
			(start -0.12065 -0.305054)
			(end -0.12065 -0.2794)
			(stroke
				(width 0.1)
				(type default)
			)
			(layer "F.Fab")
		)
		(fp_line
			(start -0.12065 -0.2794)
			(end 0.12065 -0.2794)
			(stroke
				(width 0.1)
				(type default)
			)
			(layer "F.Fab")
		)
		(fp_line
			(start -0.12065 0.2794)
			(end -0.12065 0.3048)
			(stroke
				(width 0.1)
				(type default)
			)
			(layer "F.Fab")
		)
		(fp_line
			(start -0.12065 0.3048)
			(end -0.67945 0.3048)
			(stroke
				(width 0.1)
				(type default)
			)
			(layer "F.Fab")
		)
		(fp_line
			(start 0.120396 0.2794)
			(end -0.12065 0.2794)
			(stroke
				(width 0.1)
				(type default)
			)
			(layer "F.Fab")
		)
		(fp_line
			(start 0.120396 0.3048)
			(end 0.120396 0.2794)
			(stroke
				(width 0.1)
				(type default)
			)
			(layer "F.Fab")
		)
		(fp_line
			(start 0.12065 -0.3048)
			(end 0.67945 -0.3048)
			(stroke
				(width 0.1)
				(type default)
			)
			(layer "F.Fab")
		)
		(fp_line
			(start 0.12065 -0.2794)
			(end 0.12065 -0.3048)
			(stroke
				(width 0.1)
				(type default)
			)
			(layer "F.Fab")
		)
		(fp_line
			(start 0.67945 -0.3048)
			(end 0.67945 0.3048)
			(stroke
				(width 0.1)
				(type default)
			)
			(layer "F.Fab")
		)
		(fp_line
			(start 0.67945 0.3048)
			(end 0.120396 0.3048)
			(stroke
				(width 0.1)
				(type default)
			)
			(layer "F.Fab")
		)
		(pad "1" smd circle
			(at -0.40005 0)
			(size 0 0)
			(layers "F.Cu" "F.Mask" "F.Paste")
			(net "P3V3_E1S_GATE_0")
		)
		(pad "2" smd circle
			(at 0.40005 0)
			(size 0 0)
			(layers "F.Cu" "F.Mask" "F.Paste")
			(net "GND")
		)
	)
	(footprint ""
		(layer "F.Cu")
		(at 128.401572 -128.986026)
		(property "Reference" "R2704"
			(at 0 0 0)
			(layer "F.SilkS")
			(hide yes)
			(effects
				(font
					(size 1.27 1.27)
				)
			)
		)
		(property "Value" ""
			(at 0 0 0)
			(layer "F.Fab")
			(effects
				(font
					(size 1.27 1.27)
				)
			)
		)
		(duplicate_pad_numbers_are_jumpers no)
		(fp_line
			(start -0.7874 -0.4064)
			(end 0.7874 -0.4064)
			(stroke
				(width 0.1524)
				(type default)
			)
			(layer "F.SilkS")
		)
		(fp_line
			(start -0.7874 0.4064)
			(end -0.7874 -0.4064)
			(stroke
				(width 0.1524)
				(type default)
			)
			(layer "F.SilkS")
		)
		(fp_line
			(start 0.7874 -0.4064)
			(end 0.7874 0.4064)
			(stroke
				(width 0.1524)
				(type default)
			)
			(layer "F.SilkS")
		)
		(fp_line
			(start 0.7874 0.4064)
			(end -0.7874 0.4064)
			(stroke
				(width 0.1524)
				(type default)
			)
			(layer "F.SilkS")
		)
		(fp_line
			(start -0.67945 -0.305054)
			(end -0.12065 -0.305054)
			(stroke
				(width 0.1)
				(type default)
			)
			(layer "F.Fab")
		)
		(fp_line
			(start -0.67945 0.3048)
			(end -0.67945 -0.305054)
			(stroke
				(width 0.1)
				(type default)
			)
			(layer "F.Fab")
		)
		(fp_line
			(start -0.12065 -0.305054)
			(end -0.12065 -0.2794)
			(stroke
				(width 0.1)
				(type default)
			)
			(layer "F.Fab")
		)
		(fp_line
			(start -0.12065 -0.2794)
			(end 0.12065 -0.2794)
			(stroke
				(width 0.1)
				(type default)
			)
			(layer "F.Fab")
		)
		(fp_line
			(start -0.12065 0.2794)
			(end -0.12065 0.3048)
			(stroke
				(width 0.1)
				(type default)
			)
			(layer "F.Fab")
		)
		(fp_line
			(start -0.12065 0.3048)
			(end -0.67945 0.3048)
			(stroke
				(width 0.1)
				(type default)
			)
			(layer "F.Fab")
		)
		(fp_line
			(start 0.120396 0.2794)
			(end -0.12065 0.2794)
			(stroke
				(width 0.1)
				(type default)
			)
			(layer "F.Fab")
		)
		(fp_line
			(start 0.120396 0.3048)
			(end 0.120396 0.2794)
			(stroke
				(width 0.1)
				(type default)
			)
			(layer "F.Fab")
		)
		(fp_line
			(start 0.12065 -0.3048)
			(end 0.67945 -0.3048)
			(stroke
				(width 0.1)
				(type default)
			)
			(layer "F.Fab")
		)
		(fp_line
			(start 0.12065 -0.2794)
			(end 0.12065 -0.3048)
			(stroke
				(width 0.1)
				(type default)
			)
			(layer "F.Fab")
		)
		(fp_line
			(start 0.67945 -0.3048)
			(end 0.67945 0.3048)
			(stroke
				(width 0.1)
				(type default)
			)
			(layer "F.Fab")
		)
		(fp_line
			(start 0.67945 0.3048)
			(end 0.120396 0.3048)
			(stroke
				(width 0.1)
				(type default)
			)
			(layer "F.Fab")
		)
		(pad "1" smd circle
			(at -0.40005 0)
			(size 0 0)
			(layers "F.Cu" "F.Mask" "F.Paste")
			(net "SMB_BMC_SWB_SDA_R4")
		)
		(pad "2" smd circle
			(at 0.40005 0)
			(size 0 0)
			(layers "F.Cu" "F.Mask" "F.Paste")
			(net "SMB_BMC_SWB_SDA")
		)
	)
	(footprint ""
		(layer "F.Cu")
		(at 111.332772 -139.133326)
		(property "Reference" "R538"
			(at 0 0 0)
			(layer "F.SilkS")
			(hide yes)
			(effects
				(font
					(size 1.27 1.27)
				)
			)
		)
		(property "Value" ""
			(at 0 0 0)
			(layer "F.Fab")
			(effects
				(font
					(size 1.27 1.27)
				)
			)
		)
		(duplicate_pad_numbers_are_jumpers no)
		(fp_line
			(start -0.7874 -0.4064)
			(end 0.7874 -0.4064)
			(stroke
				(width 0.1524)
				(type default)
			)
			(layer "F.SilkS")
		)
		(fp_line
			(start -0.7874 0.4064)
			(end -0.7874 -0.4064)
			(stroke
				(width 0.1524)
				(type default)
			)
			(layer "F.SilkS")
		)
		(fp_line
			(start 0.7874 -0.4064)
			(end 0.7874 0.4064)
			(stroke
				(width 0.1524)
				(type default)
			)
			(layer "F.SilkS")
		)
		(fp_line
			(start 0.7874 0.4064)
			(end -0.7874 0.4064)
			(stroke
				(width 0.1524)
				(type default)
			)
			(layer "F.SilkS")
		)
		(fp_line
			(start -0.67945 -0.305054)
			(end -0.12065 -0.305054)
			(stroke
				(width 0.1)
				(type default)
			)
			(layer "F.Fab")
		)
		(fp_line
			(start -0.67945 0.3048)
			(end -0.67945 -0.305054)
			(stroke
				(width 0.1)
				(type default)
			)
			(layer "F.Fab")
		)
		(fp_line
			(start -0.12065 -0.305054)
			(end -0.12065 -0.2794)
			(stroke
				(width 0.1)
				(type default)
			)
			(layer "F.Fab")
		)
		(fp_line
			(start -0.12065 -0.2794)
			(end 0.12065 -0.2794)
			(stroke
				(width 0.1)
				(type default)
			)
			(layer "F.Fab")
		)
		(fp_line
			(start -0.12065 0.2794)
			(end -0.12065 0.3048)
			(stroke
				(width 0.1)
				(type default)
			)
			(layer "F.Fab")
		)
		(fp_line
			(start -0.12065 0.3048)
			(end -0.67945 0.3048)
			(stroke
				(width 0.1)
				(type default)
			)
			(layer "F.Fab")
		)
		(fp_line
			(start 0.120396 0.2794)
			(end -0.12065 0.2794)
			(stroke
				(width 0.1)
				(type default)
			)
			(layer "F.Fab")
		)
		(fp_line
			(start 0.120396 0.3048)
			(end 0.120396 0.2794)
			(stroke
				(width 0.1)
				(type default)
			)
			(layer "F.Fab")
		)
		(fp_line
			(start 0.12065 -0.3048)
			(end 0.67945 -0.3048)
			(stroke
				(width 0.1)
				(type default)
			)
			(layer "F.Fab")
		)
		(fp_line
			(start 0.12065 -0.2794)
			(end 0.12065 -0.3048)
			(stroke
				(width 0.1)
				(type default)
			)
			(layer "F.Fab")
		)
		(fp_line
			(start 0.67945 -0.3048)
			(end 0.67945 0.3048)
			(stroke
				(width 0.1)
				(type default)
			)
			(layer "F.Fab")
		)
		(fp_line
			(start 0.67945 0.3048)
			(end 0.120396 0.3048)
			(stroke
				(width 0.1)
				(type default)
			)
			(layer "F.Fab")
		)
		(pad "1" smd circle
			(at -0.40005 0)
			(size 0 0)
			(layers "F.Cu" "F.Mask" "F.Paste")
			(net "P3V3_AUX")
		)
		(pad "2" smd circle
			(at 0.40005 0)
			(size 0 0)
			(layers "F.Cu" "F.Mask" "F.Paste")
			(net "PCA9548_PCIE3_ADDR1")
		)
	)
)
